(kicad_pcb
	(version 20260206)
	(generator "pcbnew")
	(generator_version "10.0")
	(general
		(thickness 1.6)
		(legacy_teardrops no)
	)
	(paper "A4")
	(title_block
		(title "Wiwynn_Tioga_Pass_MB.brd")
		(comment 1 "Tioga Pass / footprints 1896-1898 of 4770")
	)
	(layers
		(0 "F.Cu" signal "TOP")
		(4 "In1.Cu" signal "L2GND")
		(6 "In2.Cu" signal "L3")
		(8 "In3.Cu" signal "L4GND")
		(10 "In4.Cu" signal "L5")
		(12 "In5.Cu" signal "L6GND")
		(14 "In6.Cu" signal "L7VCC")
		(16 "In7.Cu" signal "L8VCC")
		(18 "In8.Cu" signal "L9GND")
		(20 "In9.Cu" signal "L10")
		(22 "In10.Cu" signal "L11GND")
		(24 "In11.Cu" signal "L12")
		(26 "In12.Cu" signal "L13GND")
		(2 "B.Cu" signal "BOTTOM")
		(9 "F.Adhes" user "F.Adhesive")
		(11 "B.Adhes" user "B.Adhesive")
		(13 "F.Paste" user "Package Geometry/Pastemask Top")
		(15 "B.Paste" user "Package Geometry/Pastemask Bottom")
		(5 "F.SilkS" user "Ref Des/Silkscreen Top")
		(7 "B.SilkS" user "Ref Des/Silkscreen Bottom")
		(1 "F.Mask" user "Board Geometry/Soldermask Top")
		(3 "B.Mask" user "Board Geometry/Soldermask Bottom")
		(17 "Dwgs.User" user "User.Drawings")
		(19 "Cmts.User" user "User.Comments")
		(21 "Eco1.User" user "User.Eco1")
		(23 "Eco2.User" user "User.Eco2")
		(25 "Edge.Cuts" user "Board Geometry/Outline")
		(27 "Margin" user)
		(31 "F.CrtYd" user "Package Geometry/Place Bound Top")
		(29 "B.CrtYd" user "Package Geometry/Place Bound Bottom")
		(35 "F.Fab" user "Ref Des/Assembly Top")
		(33 "B.Fab" user "Ref Des/Assembly Bottom")
	)
	(footprint ""
		(layer "F.Cu")
		(at 394.6525 -75.819 90)
		(property "Reference" "R7D34"
			(at 0 0 90)
			(layer "F.SilkS")
			(hide yes)
			(effects
				(font
					(size 1.27 1.27)
				)
			)
		)
		(property "Value" ""
			(at 0 0 90)
			(layer "F.Fab")
			(effects
				(font
					(size 1.27 1.27)
				)
			)
		)
		(duplicate_pad_numbers_are_jumpers no)
		(fp_poly
			(pts
				(xy -0.2794 -0.1016) (xy 0.2794 -0.1016) (xy 0.2794 0.9906) (xy -0.2794 0.9906)
			)
			(stroke
				(width 0)
				(type default)
			)
			(fill no)
			(layer "F.CrtYd")
		)
		(fp_line
			(start 0.2794 -0.1016)
			(end -0.2794 -0.1016)
			(stroke
				(width 0.1)
				(type default)
			)
			(layer "F.Fab")
		)
		(fp_line
			(start -0.2794 -0.1016)
			(end -0.2794 0.9906)
			(stroke
				(width 0.1)
				(type default)
			)
			(layer "F.Fab")
		)
		(fp_line
			(start 0.2794 0.9906)
			(end 0.2794 -0.1016)
			(stroke
				(width 0.1)
				(type default)
			)
			(layer "F.Fab")
		)
		(fp_line
			(start -0.2794 0.9906)
			(end 0.2794 0.9906)
			(stroke
				(width 0.1)
				(type default)
			)
			(layer "F.Fab")
		)
		(pad "1" smd rect
			(at 0 0 90)
			(size 0.508 0.508)
			(layers "F.Cu" "F.Mask" "F.Paste")
			(net "FM_CPU0_THERMTRIP_LVT3_R_N")
		)
		(pad "2" smd rect
			(at 0 0.889 90)
			(size 0.508 0.508)
			(layers "F.Cu" "F.Mask" "F.Paste")
			(net "FM_CPU0_THERMTRIP_LVT3_N")
		)
		(zone
			(layer "F.Cu")
			(hatch none 0.5)
			(connect_pads
				(clearance 0)
			)
			(min_thickness 0.25)
			(keepout
				(tracks allowed)
				(vias not_allowed)
				(pads allowed)
				(copperpour not_allowed)
				(footprints allowed)
			)
			(placement
				(enabled no)
				(sheetname "")
			)
			(fill
				(thermal_gap 0.5)
				(thermal_bridge_width 0.5)
				(island_removal_mode 0)
			)
			(polygon
				(pts
					(xy 394.9065 -75.565) (xy 394.9065 -76.073) (xy 395.2875 -76.073) (xy 395.2875 -75.565)
				)
			)
		)
		(zone
			(layer "F.Cu")
			(hatch none 0.5)
			(connect_pads
				(clearance 0)
			)
			(min_thickness 0.25)
			(keepout
				(tracks not_allowed)
				(vias allowed)
				(pads allowed)
				(copperpour not_allowed)
				(footprints allowed)
			)
			(placement
				(enabled no)
				(sheetname "")
			)
			(fill
				(thermal_gap 0.5)
				(thermal_bridge_width 0.5)
				(island_removal_mode 0)
			)
			(polygon
				(pts
					(xy 395.2875 -75.565) (xy 395.2875 -76.073) (xy 394.9065 -76.073) (xy 394.9065 -75.565)
				)
			)
		)
	)
	(footprint ""
		(layer "F.Cu")
		(at 180.381148 -72.96785 -90)
		(property "Reference" "C4D25"
			(at 0 0 270)
			(layer "F.SilkS")
			(hide yes)
			(effects
				(font
					(size 1.27 1.27)
				)
			)
		)
		(property "Value" ""
			(at 0 0 270)
			(layer "F.Fab")
			(effects
				(font
					(size 1.27 1.27)
				)
			)
		)
		(duplicate_pad_numbers_are_jumpers no)
		(fp_poly
			(pts
				(xy 0.3048 -0.1016) (xy 0.3048 0.9906) (xy -0.3048 0.9906) (xy -0.3048 -0.1016)
			)
			(stroke
				(width 0)
				(type default)
			)
			(fill no)
			(layer "F.CrtYd")
		)
		(fp_line
			(start -0.3048 0.9906)
			(end 0.3048 0.9906)
			(stroke
				(width 0.1)
				(type default)
			)
			(layer "F.Fab")
		)
		(fp_line
			(start 0.3048 0.9906)
			(end 0.3048 -0.1016)
			(stroke
				(width 0.1)
				(type default)
			)
			(layer "F.Fab")
		)
		(fp_line
			(start -0.3048 -0.1016)
			(end -0.3048 0.9906)
			(stroke
				(width 0.1)
				(type default)
			)
			(layer "F.Fab")
		)
		(fp_line
			(start 0.3048 -0.1016)
			(end -0.3048 -0.1016)
			(stroke
				(width 0.1)
				(type default)
			)
			(layer "F.Fab")
		)
		(pad "1" smd rect
			(at 0 0 270)
			(size 0.508 0.508)
			(layers "F.Cu" "F.Mask" "F.Paste")
			(net "VR_PVCCIN_CPU0_VD12")
		)
		(pad "2" smd rect
			(at 0 0.889 270)
			(size 0.508 0.508)
			(layers "F.Cu" "F.Mask" "F.Paste")
			(net "GND")
		)
		(zone
			(layer "F.Cu")
			(hatch none 0.5)
			(connect_pads
				(clearance 0)
			)
			(min_thickness 0.25)
			(keepout
				(tracks not_allowed)
				(vias allowed)
				(pads allowed)
				(copperpour not_allowed)
				(footprints allowed)
			)
			(placement
				(enabled no)
				(sheetname "")
			)
			(fill
				(thermal_gap 0.5)
				(thermal_bridge_width 0.5)
				(island_removal_mode 0)
			)
			(polygon
				(pts
					(xy 179.746148 -73.22185) (xy 179.746148 -72.71385) (xy 180.127148 -72.71385) (xy 180.127148 -73.22185)
				)
			)
		)
		(zone
			(layer "F.Cu")
			(hatch none 0.5)
			(connect_pads
				(clearance 0)
			)
			(min_thickness 0.25)
			(keepout
				(tracks allowed)
				(vias not_allowed)
				(pads allowed)
				(copperpour not_allowed)
				(footprints allowed)
			)
			(placement
				(enabled no)
				(sheetname "")
			)
			(fill
				(thermal_gap 0.5)
				(thermal_bridge_width 0.5)
				(island_removal_mode 0)
			)
			(polygon
				(pts
					(xy 180.127148 -73.22185) (xy 180.127148 -72.71385) (xy 179.746148 -72.71385) (xy 179.746148 -73.22185)
				)
			)
		)
	)
	(footprint ""
		(layer "F.Cu")
		(at 28.82773 -85.983318 90)
		(property "Reference" "CT13"
			(at 2.28473 -5.9182 0)
			(unlocked yes)
			(layer "F.SilkS")
			(effects
				(font
					(size 0.7874 0.5842)
					(thickness 0.1524)
				)
				(justify left)
			)
		)
		(property "Value" ""
			(at 0 0 90)
			(layer "F.Fab")
			(effects
				(font
					(size 1.27 1.27)
				)
			)
		)
		(duplicate_pad_numbers_are_jumpers no)
		(fp_poly
			(pts
				(xy 0.3048 -0.1016) (xy 0.3048 0.9906) (xy -0.3048 0.9906) (xy -0.3048 -0.1016)
			)
			(stroke
				(width 0)
				(type default)
			)
			(fill no)
			(layer "F.CrtYd")
		)
		(fp_line
			(start 0.3048 -0.1016)
			(end -0.3048 -0.1016)
			(stroke
				(width 0.1)
				(type default)
			)
			(layer "F.Fab")
		)
		(fp_line
			(start -0.3048 -0.1016)
			(end -0.3048 0.9906)
			(stroke
				(width 0.1)
				(type default)
			)
			(layer "F.Fab")
		)
		(fp_line
			(start 0.3048 0.9906)
			(end 0.3048 -0.1016)
			(stroke
				(width 0.1)
				(type default)
			)
			(layer "F.Fab")
		)
		(fp_line
			(start -0.3048 0.9906)
			(end 0.3048 0.9906)
			(stroke
				(width 0.1)
				(type default)
			)
			(layer "F.Fab")
		)
		(pad "1" smd rect
			(at 0 0 90)
			(size 0.508 0.508)
			(layers "F.Cu" "F.Mask" "F.Paste")
			(net "VR_PVCCIN_CPU1_AIREF5")
		)
		(pad "2" smd rect
			(at 0 0.889 90)
			(size 0.508 0.508)
			(layers "F.Cu" "F.Mask" "F.Paste")
			(net "GND")
		)
		(zone
			(layer "F.Cu")
			(hatch none 0.5)
			(connect_pads
				(clearance 0)
			)
			(min_thickness 0.25)
			(keepout
				(tracks allowed)
				(vias not_allowed)
				(pads allowed)
				(copperpour not_allowed)
				(footprints allowed)
			)
			(placement
				(enabled no)
				(sheetname "")
			)
			(fill
				(thermal_gap 0.5)
				(thermal_bridge_width 0.5)
				(island_removal_mode 0)
			)
			(polygon
				(pts
					(xy 29.08173 -85.729318) (xy 29.08173 -86.237318) (xy 29.46273 -86.237318) (xy 29.46273 -85.729318)
				)
			)
		)
		(zone
			(layer "F.Cu")
			(hatch none 0.5)
			(connect_pads
				(clearance 0)
			)
			(min_thickness 0.25)
			(keepout
				(tracks not_allowed)
				(vias allowed)
				(pads allowed)
				(copperpour not_allowed)
				(footprints allowed)
			)
			(placement
				(enabled no)
				(sheetname "")
			)
			(fill
				(thermal_gap 0.5)
				(thermal_bridge_width 0.5)
				(island_removal_mode 0)
			)
			(polygon
				(pts
					(xy 29.46273 -85.729318) (xy 29.46273 -86.237318) (xy 29.08173 -86.237318) (xy 29.08173 -85.729318)
				)
			)
		)
	)
)
